(kicad_pcb
	(version 20260206)
	(generator "pcbnew")
	(generator_version "10.0")
	(general
		(thickness 1.6)
		(legacy_teardrops no)
	)
	(paper "A4")
	(title_block
		(title "04192023_DAF0TMB3IC0_F0TG_MB_C_brd_V02_OCP.brd")
		(comment 1 "Grand Teton / footprints 1923-1929 of 8354")
	)
	(layers
		(0 "F.Cu" signal "TOP")
		(4 "In1.Cu" signal "GND")
		(6 "In2.Cu" signal "IN1")
		(8 "In3.Cu" signal "GND1")
		(10 "In4.Cu" signal "IN2")
		(12 "In5.Cu" signal "GND2")
		(14 "In6.Cu" signal "IN3")
		(16 "In7.Cu" signal "GND3")
		(18 "In8.Cu" signal "VCC")
		(20 "In9.Cu" signal "VCC1")
		(22 "In10.Cu" signal "GND4")
		(24 "In11.Cu" signal "IN4")
		(26 "In12.Cu" signal "GND5")
		(28 "In13.Cu" signal "IN5")
		(30 "In14.Cu" signal "GND6")
		(32 "In15.Cu" signal "IN6")
		(34 "In16.Cu" signal "GND7")
		(2 "B.Cu" signal "BOTTOM")
		(9 "F.Adhes" user "F.Adhesive")
		(11 "B.Adhes" user "B.Adhesive")
		(13 "F.Paste" user "Package Geometry/Pastemask Top")
		(15 "B.Paste" user "Package Geometry/Pastemask Bottom")
		(5 "F.SilkS" user "Ref Des/Silkscreen Top")
		(7 "B.SilkS" user "Ref Des/Silkscreen Bottom")
		(1 "F.Mask" user "Board Geometry/Soldermask Top")
		(3 "B.Mask" user "Board Geometry/Soldermask Bottom")
		(17 "Dwgs.User" user "User.Drawings")
		(19 "Cmts.User" user "User.Comments")
		(21 "Eco1.User" user "User.Eco1")
		(23 "Eco2.User" user "User.Eco2")
		(25 "Edge.Cuts" user "Board Geometry/Outline")
		(27 "Margin" user)
		(31 "F.CrtYd" user "Package Geometry/Place Bound Top")
		(29 "B.CrtYd" user "Package Geometry/Place Bound Bottom")
		(35 "F.Fab" user "Ref Des/Assembly Top")
		(33 "B.Fab" user "Ref Des/Assembly Bottom")
	)
	(footprint ""
		(layer "F.Cu")
		(at 94.358968 -184.410096 -90)
		(property "Reference" "PR486"
			(at 0 0 270)
			(layer "F.SilkS")
			(hide yes)
			(effects
				(font
					(size 1.27 1.27)
				)
			)
		)
		(property "Value" ""
			(at 0 0 270)
			(layer "F.Fab")
			(effects
				(font
					(size 1.27 1.27)
				)
			)
		)
		(duplicate_pad_numbers_are_jumpers no)
		(fp_line
			(start -0.7874 0.4064)
			(end -0.7874 -0.4064)
			(stroke
				(width 0.1524)
				(type default)
			)
			(layer "F.SilkS")
		)
		(fp_line
			(start 0.7874 0.4064)
			(end -0.7874 0.4064)
			(stroke
				(width 0.1524)
				(type default)
			)
			(layer "F.SilkS")
		)
		(fp_line
			(start -0.7874 -0.4064)
			(end 0.7874 -0.4064)
			(stroke
				(width 0.1524)
				(type default)
			)
			(layer "F.SilkS")
		)
		(fp_line
			(start 0.7874 -0.4064)
			(end 0.7874 0.4064)
			(stroke
				(width 0.1524)
				(type default)
			)
			(layer "F.SilkS")
		)
		(fp_line
			(start -0.67945 0.3048)
			(end -0.67945 -0.305054)
			(stroke
				(width 0.1)
				(type default)
			)
			(layer "F.Fab")
		)
		(fp_line
			(start -0.12065 0.3048)
			(end -0.67945 0.3048)
			(stroke
				(width 0.1)
				(type default)
			)
			(layer "F.Fab")
		)
		(fp_line
			(start 0.120396 0.3048)
			(end 0.120396 0.2794)
			(stroke
				(width 0.1)
				(type default)
			)
			(layer "F.Fab")
		)
		(fp_line
			(start 0.67945 0.3048)
			(end 0.120396 0.3048)
			(stroke
				(width 0.1)
				(type default)
			)
			(layer "F.Fab")
		)
		(fp_line
			(start -0.12065 0.2794)
			(end -0.12065 0.3048)
			(stroke
				(width 0.1)
				(type default)
			)
			(layer "F.Fab")
		)
		(fp_line
			(start 0.120396 0.2794)
			(end -0.12065 0.2794)
			(stroke
				(width 0.1)
				(type default)
			)
			(layer "F.Fab")
		)
		(fp_line
			(start -0.12065 -0.2794)
			(end 0.12065 -0.2794)
			(stroke
				(width 0.1)
				(type default)
			)
			(layer "F.Fab")
		)
		(fp_line
			(start 0.12065 -0.2794)
			(end 0.12065 -0.3048)
			(stroke
				(width 0.1)
				(type default)
			)
			(layer "F.Fab")
		)
		(fp_line
			(start 0.12065 -0.3048)
			(end 0.67945 -0.3048)
			(stroke
				(width 0.1)
				(type default)
			)
			(layer "F.Fab")
		)
		(fp_line
			(start 0.67945 -0.3048)
			(end 0.67945 0.3048)
			(stroke
				(width 0.1)
				(type default)
			)
			(layer "F.Fab")
		)
		(fp_line
			(start -0.67945 -0.305054)
			(end -0.12065 -0.305054)
			(stroke
				(width 0.1)
				(type default)
			)
			(layer "F.Fab")
		)
		(fp_line
			(start -0.12065 -0.305054)
			(end -0.12065 -0.2794)
			(stroke
				(width 0.1)
				(type default)
			)
			(layer "F.Fab")
		)
		(pad "1" smd circle
			(at -0.40005 0 270)
			(size 0 0)
			(layers "F.Cu" "F.Mask" "F.Paste")
			(net "SW_PVDDCR_CPU0_P1_SW2_RC")
		)
		(pad "2" smd circle
			(at 0.40005 0 270)
			(size 0 0)
			(layers "F.Cu" "F.Mask" "F.Paste")
			(net "GND")
		)
	)
	(footprint ""
		(layer "F.Cu")
		(at 360.681778 -177.604674 90)
		(property "Reference" "PC481_1"
			(at 0 0 90)
			(layer "F.SilkS")
			(hide yes)
			(effects
				(font
					(size 1.27 1.27)
				)
			)
		)
		(property "Value" ""
			(at 0 0 90)
			(layer "F.Fab")
			(effects
				(font
					(size 1.27 1.27)
				)
			)
		)
		(duplicate_pad_numbers_are_jumpers no)
		(fp_line
			(start 0.7874 -0.4064)
			(end 0.7874 0.4064)
			(stroke
				(width 0.1524)
				(type default)
			)
			(layer "F.SilkS")
		)
		(fp_line
			(start -0.7874 -0.4064)
			(end 0.7874 -0.4064)
			(stroke
				(width 0.1524)
				(type default)
			)
			(layer "F.SilkS")
		)
		(fp_line
			(start 0.7874 0.4064)
			(end -0.7874 0.4064)
			(stroke
				(width 0.1524)
				(type default)
			)
			(layer "F.SilkS")
		)
		(fp_line
			(start -0.7874 0.4064)
			(end -0.7874 -0.4064)
			(stroke
				(width 0.1524)
				(type default)
			)
			(layer "F.SilkS")
		)
		(fp_line
			(start -0.12065 -0.305054)
			(end -0.12065 -0.2794)
			(stroke
				(width 0.1)
				(type default)
			)
			(layer "F.Fab")
		)
		(fp_line
			(start -0.67945 -0.305054)
			(end -0.12065 -0.305054)
			(stroke
				(width 0.1)
				(type default)
			)
			(layer "F.Fab")
		)
		(fp_line
			(start 0.67945 -0.3048)
			(end 0.67945 0.3048)
			(stroke
				(width 0.1)
				(type default)
			)
			(layer "F.Fab")
		)
		(fp_line
			(start 0.12065 -0.3048)
			(end 0.67945 -0.3048)
			(stroke
				(width 0.1)
				(type default)
			)
			(layer "F.Fab")
		)
		(fp_line
			(start 0.12065 -0.2794)
			(end 0.12065 -0.3048)
			(stroke
				(width 0.1)
				(type default)
			)
			(layer "F.Fab")
		)
		(fp_line
			(start -0.12065 -0.2794)
			(end 0.12065 -0.2794)
			(stroke
				(width 0.1)
				(type default)
			)
			(layer "F.Fab")
		)
		(fp_line
			(start 0.120396 0.2794)
			(end -0.12065 0.2794)
			(stroke
				(width 0.1)
				(type default)
			)
			(layer "F.Fab")
		)
		(fp_line
			(start -0.12065 0.2794)
			(end -0.12065 0.3048)
			(stroke
				(width 0.1)
				(type default)
			)
			(layer "F.Fab")
		)
		(fp_line
			(start 0.67945 0.3048)
			(end 0.120396 0.3048)
			(stroke
				(width 0.1)
				(type default)
			)
			(layer "F.Fab")
		)
		(fp_line
			(start 0.120396 0.3048)
			(end 0.120396 0.2794)
			(stroke
				(width 0.1)
				(type default)
			)
			(layer "F.Fab")
		)
		(fp_line
			(start -0.12065 0.3048)
			(end -0.67945 0.3048)
			(stroke
				(width 0.1)
				(type default)
			)
			(layer "F.Fab")
		)
		(fp_line
			(start -0.67945 0.3048)
			(end -0.67945 -0.305054)
			(stroke
				(width 0.1)
				(type default)
			)
			(layer "F.Fab")
		)
		(pad "1" smd circle
			(at -0.40005 0 90)
			(size 0 0)
			(layers "F.Cu" "F.Mask" "F.Paste")
			(net "SW_P12V_AUX_PVDDCR_CPU0_P0_FLT")
		)
		(pad "2" smd circle
			(at 0.40005 0 90)
			(size 0 0)
			(layers "F.Cu" "F.Mask" "F.Paste")
			(net "GND")
		)
	)
	(footprint ""
		(layer "F.Cu")
		(at 12.860274 -389.044434 -90)
		(property "Reference" "PC6609_09P1_1"
			(at 0 0 270)
			(layer "F.SilkS")
			(hide yes)
			(effects
				(font
					(size 1.27 1.27)
				)
			)
		)
		(property "Value" ""
			(at 0 0 270)
			(layer "F.Fab")
			(effects
				(font
					(size 1.27 1.27)
				)
			)
		)
		(duplicate_pad_numbers_are_jumpers no)
		(fp_line
			(start -0.7874 0.4064)
			(end -0.7874 -0.4064)
			(stroke
				(width 0.1524)
				(type default)
			)
			(layer "F.SilkS")
		)
		(fp_line
			(start 0.7874 0.4064)
			(end -0.7874 0.4064)
			(stroke
				(width 0.1524)
				(type default)
			)
			(layer "F.SilkS")
		)
		(fp_line
			(start -0.7874 -0.4064)
			(end 0.7874 -0.4064)
			(stroke
				(width 0.1524)
				(type default)
			)
			(layer "F.SilkS")
		)
		(fp_line
			(start 0.7874 -0.4064)
			(end 0.7874 0.4064)
			(stroke
				(width 0.1524)
				(type default)
			)
			(layer "F.SilkS")
		)
		(fp_line
			(start -0.67945 0.3048)
			(end -0.67945 -0.305054)
			(stroke
				(width 0.1)
				(type default)
			)
			(layer "F.Fab")
		)
		(fp_line
			(start -0.12065 0.3048)
			(end -0.67945 0.3048)
			(stroke
				(width 0.1)
				(type default)
			)
			(layer "F.Fab")
		)
		(fp_line
			(start 0.120396 0.3048)
			(end 0.120396 0.2794)
			(stroke
				(width 0.1)
				(type default)
			)
			(layer "F.Fab")
		)
		(fp_line
			(start 0.67945 0.3048)
			(end 0.120396 0.3048)
			(stroke
				(width 0.1)
				(type default)
			)
			(layer "F.Fab")
		)
		(fp_line
			(start -0.12065 0.2794)
			(end -0.12065 0.3048)
			(stroke
				(width 0.1)
				(type default)
			)
			(layer "F.Fab")
		)
		(fp_line
			(start 0.120396 0.2794)
			(end -0.12065 0.2794)
			(stroke
				(width 0.1)
				(type default)
			)
			(layer "F.Fab")
		)
		(fp_line
			(start -0.12065 -0.2794)
			(end 0.12065 -0.2794)
			(stroke
				(width 0.1)
				(type default)
			)
			(layer "F.Fab")
		)
		(fp_line
			(start 0.12065 -0.2794)
			(end 0.12065 -0.3048)
			(stroke
				(width 0.1)
				(type default)
			)
			(layer "F.Fab")
		)
		(fp_line
			(start 0.12065 -0.3048)
			(end 0.67945 -0.3048)
			(stroke
				(width 0.1)
				(type default)
			)
			(layer "F.Fab")
		)
		(fp_line
			(start 0.67945 -0.3048)
			(end 0.67945 0.3048)
			(stroke
				(width 0.1)
				(type default)
			)
			(layer "F.Fab")
		)
		(fp_line
			(start -0.67945 -0.305054)
			(end -0.12065 -0.305054)
			(stroke
				(width 0.1)
				(type default)
			)
			(layer "F.Fab")
		)
		(fp_line
			(start -0.12065 -0.305054)
			(end -0.12065 -0.2794)
			(stroke
				(width 0.1)
				(type default)
			)
			(layer "F.Fab")
		)
		(pad "1" smd circle
			(at -0.40005 0 270)
			(size 0 0)
			(layers "F.Cu" "F.Mask" "F.Paste")
			(net "P0V9_RETIMER_CPU1_PVCC")
		)
		(pad "2" smd circle
			(at 0.40005 0 270)
			(size 0 0)
			(layers "F.Cu" "F.Mask" "F.Paste")
			(net "GND")
		)
	)
	(footprint ""
		(layer "F.Cu")
		(at 169.368724 -376.067828)
		(property "Reference" "C745"
			(at 0 0 0)
			(layer "F.SilkS")
			(hide yes)
			(effects
				(font
					(size 1.27 1.27)
				)
			)
		)
		(property "Value" ""
			(at 0 0 0)
			(layer "F.Fab")
			(effects
				(font
					(size 1.27 1.27)
				)
			)
		)
		(duplicate_pad_numbers_are_jumpers no)
		(fp_line
			(start -0.299974 -0.150114)
			(end 0.299974 -0.150114)
			(stroke
				(width 0.1)
				(type default)
			)
			(layer "F.Fab")
		)
		(fp_line
			(start -0.299974 0.150114)
			(end -0.299974 -0.150114)
			(stroke
				(width 0.1)
				(type default)
			)
			(layer "F.Fab")
		)
		(fp_line
			(start 0.299974 -0.150114)
			(end 0.299974 0.150114)
			(stroke
				(width 0.1)
				(type default)
			)
			(layer "F.Fab")
		)
		(fp_line
			(start 0.299974 0.150114)
			(end -0.299974 0.150114)
			(stroke
				(width 0.1)
				(type default)
			)
			(layer "F.Fab")
		)
		(pad "1" smd rect
			(at -0.2667 0)
			(size 0.3048 0.381)
			(layers "F.Cu" "F.Mask" "F.Paste")
			(net "P5E_CPU1_P2_TX_C_DP<14>")
		)
		(pad "2" smd rect
			(at 0.2667 0)
			(size 0.3048 0.381)
			(layers "F.Cu" "F.Mask" "F.Paste")
			(net "P5E_CPU1_P2_TX_DP<14>")
		)
	)
	(footprint ""
		(layer "F.Cu")
		(at 8.42772 -76.144628 90)
		(property "Reference" "C1875"
			(at 0 0 90)
			(layer "F.SilkS")
			(hide yes)
			(effects
				(font
					(size 1.27 1.27)
				)
			)
		)
		(property "Value" ""
			(at 0 0 90)
			(layer "F.Fab")
			(effects
				(font
					(size 1.27 1.27)
				)
			)
		)
		(duplicate_pad_numbers_are_jumpers no)
		(fp_line
			(start 0.7874 -0.4064)
			(end 0.7874 0.4064)
			(stroke
				(width 0.1524)
				(type default)
			)
			(layer "F.SilkS")
		)
		(fp_line
			(start -0.7874 -0.4064)
			(end 0.7874 -0.4064)
			(stroke
				(width 0.1524)
				(type default)
			)
			(layer "F.SilkS")
		)
		(fp_line
			(start 0.7874 0.4064)
			(end -0.7874 0.4064)
			(stroke
				(width 0.1524)
				(type default)
			)
			(layer "F.SilkS")
		)
		(fp_line
			(start -0.7874 0.4064)
			(end -0.7874 -0.4064)
			(stroke
				(width 0.1524)
				(type default)
			)
			(layer "F.SilkS")
		)
		(fp_line
			(start -0.12065 -0.305054)
			(end -0.12065 -0.2794)
			(stroke
				(width 0.1)
				(type default)
			)
			(layer "F.Fab")
		)
		(fp_line
			(start -0.67945 -0.305054)
			(end -0.12065 -0.305054)
			(stroke
				(width 0.1)
				(type default)
			)
			(layer "F.Fab")
		)
		(fp_line
			(start 0.67945 -0.3048)
			(end 0.67945 0.3048)
			(stroke
				(width 0.1)
				(type default)
			)
			(layer "F.Fab")
		)
		(fp_line
			(start 0.12065 -0.3048)
			(end 0.67945 -0.3048)
			(stroke
				(width 0.1)
				(type default)
			)
			(layer "F.Fab")
		)
		(fp_line
			(start 0.12065 -0.2794)
			(end 0.12065 -0.3048)
			(stroke
				(width 0.1)
				(type default)
			)
			(layer "F.Fab")
		)
		(fp_line
			(start -0.12065 -0.2794)
			(end 0.12065 -0.2794)
			(stroke
				(width 0.1)
				(type default)
			)
			(layer "F.Fab")
		)
		(fp_line
			(start 0.120396 0.2794)
			(end -0.12065 0.2794)
			(stroke
				(width 0.1)
				(type default)
			)
			(layer "F.Fab")
		)
		(fp_line
			(start -0.12065 0.2794)
			(end -0.12065 0.3048)
			(stroke
				(width 0.1)
				(type default)
			)
			(layer "F.Fab")
		)
		(fp_line
			(start 0.67945 0.3048)
			(end 0.120396 0.3048)
			(stroke
				(width 0.1)
				(type default)
			)
			(layer "F.Fab")
		)
		(fp_line
			(start 0.120396 0.3048)
			(end 0.120396 0.2794)
			(stroke
				(width 0.1)
				(type default)
			)
			(layer "F.Fab")
		)
		(fp_line
			(start -0.12065 0.3048)
			(end -0.67945 0.3048)
			(stroke
				(width 0.1)
				(type default)
			)
			(layer "F.Fab")
		)
		(fp_line
			(start -0.67945 0.3048)
			(end -0.67945 -0.305054)
			(stroke
				(width 0.1)
				(type default)
			)
			(layer "F.Fab")
		)
		(pad "1" smd circle
			(at -0.40005 0 90)
			(size 0 0)
			(layers "F.Cu" "F.Mask" "F.Paste")
			(net "P3V3_AUX")
		)
		(pad "2" smd circle
			(at 0.40005 0 90)
			(size 0 0)
			(layers "F.Cu" "F.Mask" "F.Paste")
			(net "GND")
		)
	)
	(footprint ""
		(layer "F.Cu")
		(at 213.54288 -34.508948 180)
		(property "Reference" "R3576"
			(at 0 0 180)
			(layer "F.SilkS")
			(hide yes)
			(effects
				(font
					(size 1.27 1.27)
				)
			)
		)
		(property "Value" ""
			(at 0 0 180)
			(layer "F.Fab")
			(effects
				(font
					(size 1.27 1.27)
				)
			)
		)
		(duplicate_pad_numbers_are_jumpers no)
		(fp_line
			(start 0.7874 0.4064)
			(end -0.7874 0.4064)
			(stroke
				(width 0.1524)
				(type default)
			)
			(layer "F.SilkS")
		)
		(fp_line
			(start 0.7874 -0.4064)
			(end 0.7874 0.4064)
			(stroke
				(width 0.1524)
				(type default)
			)
			(layer "F.SilkS")
		)
		(fp_line
			(start -0.7874 0.4064)
			(end -0.7874 -0.4064)
			(stroke
				(width 0.1524)
				(type default)
			)
			(layer "F.SilkS")
		)
		(fp_line
			(start -0.7874 -0.4064)
			(end 0.7874 -0.4064)
			(stroke
				(width 0.1524)
				(type default)
			)
			(layer "F.SilkS")
		)
		(fp_line
			(start 0.67945 0.3048)
			(end 0.120396 0.3048)
			(stroke
				(width 0.1)
				(type default)
			)
			(layer "F.Fab")
		)
		(fp_line
			(start 0.67945 -0.3048)
			(end 0.67945 0.3048)
			(stroke
				(width 0.1)
				(type default)
			)
			(layer "F.Fab")
		)
		(fp_line
			(start 0.12065 -0.2794)
			(end 0.12065 -0.3048)
			(stroke
				(width 0.1)
				(type default)
			)
			(layer "F.Fab")
		)
		(fp_line
			(start 0.12065 -0.3048)
			(end 0.67945 -0.3048)
			(stroke
				(width 0.1)
				(type default)
			)
			(layer "F.Fab")
		)
		(fp_line
			(start 0.120396 0.3048)
			(end 0.120396 0.2794)
			(stroke
				(width 0.1)
				(type default)
			)
			(layer "F.Fab")
		)
		(fp_line
			(start 0.120396 0.2794)
			(end -0.12065 0.2794)
			(stroke
				(width 0.1)
				(type default)
			)
			(layer "F.Fab")
		)
		(fp_line
			(start -0.12065 0.3048)
			(end -0.67945 0.3048)
			(stroke
				(width 0.1)
				(type default)
			)
			(layer "F.Fab")
		)
		(fp_line
			(start -0.12065 0.2794)
			(end -0.12065 0.3048)
			(stroke
				(width 0.1)
				(type default)
			)
			(layer "F.Fab")
		)
		(fp_line
			(start -0.12065 -0.2794)
			(end 0.12065 -0.2794)
			(stroke
				(width 0.1)
				(type default)
			)
			(layer "F.Fab")
		)
		(fp_line
			(start -0.12065 -0.305054)
			(end -0.12065 -0.2794)
			(stroke
				(width 0.1)
				(type default)
			)
			(layer "F.Fab")
		)
		(fp_line
			(start -0.67945 0.3048)
			(end -0.67945 -0.305054)
			(stroke
				(width 0.1)
				(type default)
			)
			(layer "F.Fab")
		)
		(fp_line
			(start -0.67945 -0.305054)
			(end -0.12065 -0.305054)
			(stroke
				(width 0.1)
				(type default)
			)
			(layer "F.Fab")
		)
		(pad "1" smd circle
			(at -0.40005 0 180)
			(size 0 0)
			(layers "F.Cu" "F.Mask" "F.Paste")
			(net "SMB_INA230_5_3V3AUX_SCL_R")
		)
		(pad "2" smd circle
			(at 0.40005 0 180)
			(size 0 0)
			(layers "F.Cu" "F.Mask" "F.Paste")
			(net "SMB_INA230_5_3V3AUX_SCL_R1")
		)
	)
	(footprint ""
		(layer "F.Cu")
		(at 18.702782 -136.985502)
		(property "Reference" "R3337"
			(at 0 0 0)
			(layer "F.SilkS")
			(hide yes)
			(effects
				(font
					(size 1.27 1.27)
				)
			)
		)
		(property "Value" ""
			(at 0 0 0)
			(layer "F.Fab")
			(effects
				(font
					(size 1.27 1.27)
				)
			)
		)
		(duplicate_pad_numbers_are_jumpers no)
		(fp_line
			(start -0.7874 -0.4064)
			(end 0.7874 -0.4064)
			(stroke
				(width 0.1524)
				(type default)
			)
			(layer "F.SilkS")
		)
		(fp_line
			(start -0.7874 0.4064)
			(end -0.7874 -0.4064)
			(stroke
				(width 0.1524)
				(type default)
			)
			(layer "F.SilkS")
		)
		(fp_line
			(start 0.7874 -0.4064)
			(end 0.7874 0.4064)
			(stroke
				(width 0.1524)
				(type default)
			)
			(layer "F.SilkS")
		)
		(fp_line
			(start 0.7874 0.4064)
			(end -0.7874 0.4064)
			(stroke
				(width 0.1524)
				(type default)
			)
			(layer "F.SilkS")
		)
		(fp_line
			(start -0.67945 -0.305054)
			(end -0.12065 -0.305054)
			(stroke
				(width 0.1)
				(type default)
			)
			(layer "F.Fab")
		)
		(fp_line
			(start -0.67945 0.3048)
			(end -0.67945 -0.305054)
			(stroke
				(width 0.1)
				(type default)
			)
			(layer "F.Fab")
		)
		(fp_line
			(start -0.12065 -0.305054)
			(end -0.12065 -0.2794)
			(stroke
				(width 0.1)
				(type default)
			)
			(layer "F.Fab")
		)
		(fp_line
			(start -0.12065 -0.2794)
			(end 0.12065 -0.2794)
			(stroke
				(width 0.1)
				(type default)
			)
			(layer "F.Fab")
		)
		(fp_line
			(start -0.12065 0.2794)
			(end -0.12065 0.3048)
			(stroke
				(width 0.1)
				(type default)
			)
			(layer "F.Fab")
		)
		(fp_line
			(start -0.12065 0.3048)
			(end -0.67945 0.3048)
			(stroke
				(width 0.1)
				(type default)
			)
			(layer "F.Fab")
		)
		(fp_line
			(start 0.120396 0.2794)
			(end -0.12065 0.2794)
			(stroke
				(width 0.1)
				(type default)
			)
			(layer "F.Fab")
		)
		(fp_line
			(start 0.120396 0.3048)
			(end 0.120396 0.2794)
			(stroke
				(width 0.1)
				(type default)
			)
			(layer "F.Fab")
		)
		(fp_line
			(start 0.12065 -0.3048)
			(end 0.67945 -0.3048)
			(stroke
				(width 0.1)
				(type default)
			)
			(layer "F.Fab")
		)
		(fp_line
			(start 0.12065 -0.2794)
			(end 0.12065 -0.3048)
			(stroke
				(width 0.1)
				(type default)
			)
			(layer "F.Fab")
		)
		(fp_line
			(start 0.67945 -0.3048)
			(end 0.67945 0.3048)
			(stroke
				(width 0.1)
				(type default)
			)
			(layer "F.Fab")
		)
		(fp_line
			(start 0.67945 0.3048)
			(end 0.120396 0.3048)
			(stroke
				(width 0.1)
				(type default)
			)
			(layer "F.Fab")
		)
		(pad "1" smd circle
			(at -0.40005 0)
			(size 0 0)
			(layers "F.Cu" "F.Mask" "F.Paste")
			(net "CLK_100M_GPU_FPGA_DP_R")
		)
		(pad "2" smd circle
			(at 0.40005 0)
			(size 0 0)
			(layers "F.Cu" "F.Mask" "F.Paste")
			(net "CLK_100M_GPU_FPGA_DP")
		)
	)
)
